(kicad_pcb
	(version 20241229)
	(generator "pcbnew")
	(generator_version "9.0")
	(general
		(thickness 1.599998)
		(legacy_teardrops no)
	)
	(paper "A4")
	(title_block
		(date "2023-02-12")
		(rev "1.1.5")
		(comment 9 "footprints 327-332 of 473")
	)
	(layers
		(0 "F.Cu" signal)
		(4 "In1.Cu" power "In1.GND")
		(6 "In2.Cu" signal)
		(8 "In3.Cu" power "In3.GND")
		(10 "In4.Cu" power "In4.VCC")
		(12 "In5.Cu" signal)
		(14 "In6.Cu" power "In6.VCC")
		(2 "B.Cu" signal)
		(9 "F.Adhes" user "F.Adhesive")
		(11 "B.Adhes" user "B.Adhesive")
		(13 "F.Paste" user)
		(15 "B.Paste" user)
		(5 "F.SilkS" user "F.Silkscreen")
		(7 "B.SilkS" user "B.Silkscreen")
		(1 "F.Mask" user)
		(3 "B.Mask" user)
		(17 "Dwgs.User" user "User.Drawings")
		(19 "Cmts.User" user "User.Comments")
		(21 "Eco1.User" user "User.Eco1")
		(23 "Eco2.User" user "User.Eco2")
		(25 "Edge.Cuts" user)
		(27 "Margin" user)
		(31 "F.CrtYd" user "F.Courtyard")
		(29 "B.CrtYd" user "B.Courtyard")
		(35 "F.Fab" user)
		(33 "B.Fab" user)
	)
	(footprint "antmicro-footprints:C_0603_1608Metric"
		(layer "B.Cu")
		(at 159.036328 87.247157)
		(descr "Capacitor SMD 0603")
		(tags "capacitor 0603")
		(property "Reference" "C27"
			(at 1.063672 -0.547157 180)
			(layer "B.SilkS")
			(effects
				(font
					(size 0.7 0.7)
					(thickness 0.15)
				)
				(justify left bottom mirror)
			)
		)
		(property "Value" "C_47u_0603"
			(at 0 -1.6 180)
			(layer "B.Fab")
			(effects
				(font
					(size 0.7 0.7)
					(thickness 0.15)
				)
				(justify left bottom mirror)
			)
		)
		(property "Description" " "
			(at 0 0 0)
			(layer "F.Fab")
			(hide yes)
			(effects
				(font
					(size 1.27 1.27)
					(thickness 0.15)
				)
			)
		)
		(property "Author" "Antmicro"
			(at 0 0 0)
			(layer "B.Fab")
			(hide yes)
			(effects
				(font
					(size 1 1)
					(thickness 0.15)
				)
				(justify mirror)
			)
		)
		(property "Dielectric" ""
			(at 0 0 0)
			(layer "B.Fab")
			(hide yes)
			(effects
				(font
					(size 1 1)
					(thickness 0.15)
				)
				(justify mirror)
			)
		)
		(property "License" "Apache-2.0"
			(at 0 0 0)
			(layer "B.Fab")
			(hide yes)
			(effects
				(font
					(size 1 1)
					(thickness 0.15)
				)
				(justify mirror)
			)
		)
		(property "MPN" "GRM188R60J476ME15D"
			(at 0 0 0)
			(layer "B.Fab")
			(hide yes)
			(effects
				(font
					(size 1 1)
					(thickness 0.15)
				)
				(justify mirror)
			)
		)
		(property "Manufacturer" "Murata"
			(at 0 0 0)
			(layer "B.Fab")
			(hide yes)
			(effects
				(font
					(size 1 1)
					(thickness 0.15)
				)
				(justify mirror)
			)
		)
		(property "Val" "47u"
			(at 0 0 0)
			(layer "B.Fab")
			(hide yes)
			(effects
				(font
					(size 1 1)
					(thickness 0.15)
				)
				(justify mirror)
			)
		)
		(property "Voltage" ""
			(at 0 0 0)
			(layer "B.Fab")
			(hide yes)
			(effects
				(font
					(size 1 1)
					(thickness 0.15)
				)
				(justify mirror)
			)
		)
		(sheetname "FPGA power")
		(sheetfile "fpga-power.kicad_sch")
		(attr smd)
		(fp_line
			(start -0.3 -0.3)
			(end 0.3 -0.3)
			(stroke
				(width 0.15)
				(type solid)
			)
			(layer "B.SilkS")
		)
		(fp_line
			(start -0.3 0.3)
			(end 0.3 0.3)
			(stroke
				(width 0.15)
				(type solid)
			)
			(layer "B.SilkS")
		)
		(fp_rect
			(start -1.24 0.7)
			(end 1.24 -0.7)
			(stroke
				(width 0.05)
				(type solid)
			)
			(fill no)
			(layer "B.CrtYd")
		)
		(fp_rect
			(start -0.8 0.4)
			(end 0.8 -0.4)
			(stroke
				(width 0.15)
				(type solid)
			)
			(fill no)
			(layer "B.Fab")
		)
		(pad "1" smd roundrect
			(at -0.7 0)
			(size 0.6 0.8)
			(layers "B.Cu" "B.Mask" "B.Paste")
			(roundrect_rratio 0.2)
			(net 66 "VDDQ")
			(pintype "passive")
		)
		(pad "2" smd roundrect
			(at 0.7 0)
			(size 0.6 0.8)
			(layers "B.Cu" "B.Mask" "B.Paste")
			(roundrect_rratio 0.2)
			(net 5 "GND")
			(pintype "passive")
		)
	)
	(footprint "antmicro-footprints:C_0603_1608Metric"
		(layer "B.Cu")
		(at 161.411328 99.247157 180)
		(descr "Capacitor SMD 0603")
		(tags "capacitor 0603")
		(property "Reference" "C96"
			(at -1.088672 -1.352843 0)
			(layer "B.SilkS")
			(effects
				(font
					(size 0.7 0.7)
					(thickness 0.15)
				)
				(justify left bottom mirror)
			)
		)
		(property "Value" "C_47u_0603"
			(at 0 -1.6 0)
			(layer "B.Fab")
			(effects
				(font
					(size 0.7 0.7)
					(thickness 0.15)
				)
				(justify left bottom mirror)
			)
		)
		(property "Description" " "
			(at 0 0 180)
			(layer "F.Fab")
			(hide yes)
			(effects
				(font
					(size 1.27 1.27)
					(thickness 0.15)
				)
			)
		)
		(property "Author" "Antmicro"
			(at 322.822656 198.494314 0)
			(layer "B.Fab")
			(hide yes)
			(effects
				(font
					(size 1 1)
					(thickness 0.15)
				)
				(justify mirror)
			)
		)
		(property "Dielectric" ""
			(at 322.822656 198.494314 0)
			(layer "B.Fab")
			(hide yes)
			(effects
				(font
					(size 1 1)
					(thickness 0.15)
				)
				(justify mirror)
			)
		)
		(property "License" "Apache-2.0"
			(at 322.822656 198.494314 0)
			(layer "B.Fab")
			(hide yes)
			(effects
				(font
					(size 1 1)
					(thickness 0.15)
				)
				(justify mirror)
			)
		)
		(property "MPN" "GRM188R60J476ME15D"
			(at 322.822656 198.494314 0)
			(layer "B.Fab")
			(hide yes)
			(effects
				(font
					(size 1 1)
					(thickness 0.15)
				)
				(justify mirror)
			)
		)
		(property "Manufacturer" "Murata"
			(at 322.822656 198.494314 0)
			(layer "B.Fab")
			(hide yes)
			(effects
				(font
					(size 1 1)
					(thickness 0.15)
				)
				(justify mirror)
			)
		)
		(property "Val" "47u"
			(at 322.822656 198.494314 0)
			(layer "B.Fab")
			(hide yes)
			(effects
				(font
					(size 1 1)
					(thickness 0.15)
				)
				(justify mirror)
			)
		)
		(property "Voltage" ""
			(at 322.822656 198.494314 0)
			(layer "B.Fab")
			(hide yes)
			(effects
				(font
					(size 1 1)
					(thickness 0.15)
				)
				(justify mirror)
			)
		)
		(sheetname "FPGA power")
		(sheetfile "fpga-power.kicad_sch")
		(attr smd)
		(fp_line
			(start -0.3 0.3)
			(end 0.3 0.3)
			(stroke
				(width 0.15)
				(type solid)
			)
			(layer "B.SilkS")
		)
		(fp_line
			(start -0.3 -0.3)
			(end 0.3 -0.3)
			(stroke
				(width 0.15)
				(type solid)
			)
			(layer "B.SilkS")
		)
		(fp_rect
			(start -1.24 0.7)
			(end 1.24 -0.7)
			(stroke
				(width 0.05)
				(type solid)
			)
			(fill no)
			(layer "B.CrtYd")
		)
		(fp_rect
			(start -0.8 0.4)
			(end 0.8 -0.4)
			(stroke
				(width 0.15)
				(type solid)
			)
			(fill no)
			(layer "B.Fab")
		)
		(pad "1" smd roundrect
			(at -0.7 0 180)
			(size 0.6 0.8)
			(layers "B.Cu" "B.Mask" "B.Paste")
			(roundrect_rratio 0.2)
			(net 459 "3V3_SYS")
			(pintype "passive")
		)
		(pad "2" smd roundrect
			(at 0.7 0 180)
			(size 0.6 0.8)
			(layers "B.Cu" "B.Mask" "B.Paste")
			(roundrect_rratio 0.2)
			(net 5 "GND")
			(pintype "passive")
		)
	)
	(footprint "antmicro-footprints:C_0603_1608Metric"
		(layer "B.Cu")
		(at 175.036328 95.497157 90)
		(descr "Capacitor SMD 0603")
		(tags "capacitor 0603")
		(property "Reference" "C93"
			(at 0.397157 1.363672 270)
			(layer "B.SilkS")
			(effects
				(font
					(size 0.7 0.7)
					(thickness 0.15)
				)
				(justify left bottom mirror)
			)
		)
		(property "Value" "C_47u_0603"
			(at 0 -1.6 270)
			(layer "B.Fab")
			(effects
				(font
					(size 0.7 0.7)
					(thickness 0.15)
				)
				(justify left bottom mirror)
			)
		)
		(property "Description" " "
			(at 0 0 90)
			(layer "F.Fab")
			(hide yes)
			(effects
				(font
					(size 1.27 1.27)
					(thickness 0.15)
				)
			)
		)
		(property "Author" "Antmicro"
			(at 270.533485 -79.539171 0)
			(layer "B.Fab")
			(hide yes)
			(effects
				(font
					(size 1 1)
					(thickness 0.15)
				)
				(justify mirror)
			)
		)
		(property "Dielectric" ""
			(at 270.533485 -79.539171 0)
			(layer "B.Fab")
			(hide yes)
			(effects
				(font
					(size 1 1)
					(thickness 0.15)
				)
				(justify mirror)
			)
		)
		(property "License" "Apache-2.0"
			(at 270.533485 -79.539171 0)
			(layer "B.Fab")
			(hide yes)
			(effects
				(font
					(size 1 1)
					(thickness 0.15)
				)
				(justify mirror)
			)
		)
		(property "MPN" "GRM188R60J476ME15D"
			(at 270.533485 -79.539171 0)
			(layer "B.Fab")
			(hide yes)
			(effects
				(font
					(size 1 1)
					(thickness 0.15)
				)
				(justify mirror)
			)
		)
		(property "Manufacturer" "Murata"
			(at 270.533485 -79.539171 0)
			(layer "B.Fab")
			(hide yes)
			(effects
				(font
					(size 1 1)
					(thickness 0.15)
				)
				(justify mirror)
			)
		)
		(property "Val" "47u"
			(at 270.533485 -79.539171 0)
			(layer "B.Fab")
			(hide yes)
			(effects
				(font
					(size 1 1)
					(thickness 0.15)
				)
				(justify mirror)
			)
		)
		(property "Voltage" ""
			(at 270.533485 -79.539171 0)
			(layer "B.Fab")
			(hide yes)
			(effects
				(font
					(size 1 1)
					(thickness 0.15)
				)
				(justify mirror)
			)
		)
		(sheetname "FPGA power")
		(sheetfile "fpga-power.kicad_sch")
		(attr smd)
		(fp_line
			(start -0.3 -0.3)
			(end 0.3 -0.3)
			(stroke
				(width 0.15)
				(type solid)
			)
			(layer "B.SilkS")
		)
		(fp_line
			(start -0.3 0.3)
			(end 0.3 0.3)
			(stroke
				(width 0.15)
				(type solid)
			)
			(layer "B.SilkS")
		)
		(fp_rect
			(start -1.24 0.7)
			(end 1.24 -0.7)
			(stroke
				(width 0.05)
				(type solid)
			)
			(fill no)
			(layer "B.CrtYd")
		)
		(fp_rect
			(start -0.8 0.4)
			(end 0.8 -0.4)
			(stroke
				(width 0.15)
				(type solid)
			)
			(fill no)
			(layer "B.Fab")
		)
		(pad "1" smd roundrect
			(at -0.7 0 90)
			(size 0.6 0.8)
			(layers "B.Cu" "B.Mask" "B.Paste")
			(roundrect_rratio 0.2)
			(net 459 "3V3_SYS")
			(pintype "passive")
		)
		(pad "2" smd roundrect
			(at 0.7 0 90)
			(size 0.6 0.8)
			(layers "B.Cu" "B.Mask" "B.Paste")
			(roundrect_rratio 0.2)
			(net 5 "GND")
			(pintype "passive")
		)
	)
	(footprint "antmicro-footprints:C_0603_1608Metric"
		(layer "B.Cu")
		(at 179.661328 102.247157 -90)
		(descr "Capacitor SMD 0603")
		(tags "capacitor 0603")
		(property "Reference" "C94"
			(at -1.047157 -1.338672 90)
			(layer "B.SilkS")
			(effects
				(font
					(size 0.7 0.7)
					(thickness 0.15)
				)
				(justify left bottom mirror)
			)
		)
		(property "Value" "C_47u_0603"
			(at 0 -1.6 90)
			(layer "B.Fab")
			(effects
				(font
					(size 0.7 0.7)
					(thickness 0.15)
				)
				(justify left bottom mirror)
			)
		)
		(property "Description" " "
			(at 0 0 270)
			(layer "F.Fab")
			(hide yes)
			(effects
				(font
					(size 1.27 1.27)
					(thickness 0.15)
				)
			)
		)
		(property "Author" "Antmicro"
			(at 77.414171 281.908485 0)
			(layer "B.Fab")
			(hide yes)
			(effects
				(font
					(size 1 1)
					(thickness 0.15)
				)
				(justify mirror)
			)
		)
		(property "Dielectric" ""
			(at 77.414171 281.908485 0)
			(layer "B.Fab")
			(hide yes)
			(effects
				(font
					(size 1 1)
					(thickness 0.15)
				)
				(justify mirror)
			)
		)
		(property "License" "Apache-2.0"
			(at 77.414171 281.908485 0)
			(layer "B.Fab")
			(hide yes)
			(effects
				(font
					(size 1 1)
					(thickness 0.15)
				)
				(justify mirror)
			)
		)
		(property "MPN" "GRM188R60J476ME15D"
			(at 77.414171 281.908485 0)
			(layer "B.Fab")
			(hide yes)
			(effects
				(font
					(size 1 1)
					(thickness 0.15)
				)
				(justify mirror)
			)
		)
		(property "Manufacturer" "Murata"
			(at 77.414171 281.908485 0)
			(layer "B.Fab")
			(hide yes)
			(effects
				(font
					(size 1 1)
					(thickness 0.15)
				)
				(justify mirror)
			)
		)
		(property "Val" "47u"
			(at 77.414171 281.908485 0)
			(layer "B.Fab")
			(hide yes)
			(effects
				(font
					(size 1 1)
					(thickness 0.15)
				)
				(justify mirror)
			)
		)
		(property "Voltage" ""
			(at 77.414171 281.908485 0)
			(layer "B.Fab")
			(hide yes)
			(effects
				(font
					(size 1 1)
					(thickness 0.15)
				)
				(justify mirror)
			)
		)
		(sheetname "FPGA power")
		(sheetfile "fpga-power.kicad_sch")
		(attr smd)
		(fp_line
			(start -0.3 0.3)
			(end 0.3 0.3)
			(stroke
				(width 0.15)
				(type solid)
			)
			(layer "B.SilkS")
		)
		(fp_line
			(start -0.3 -0.3)
			(end 0.3 -0.3)
			(stroke
				(width 0.15)
				(type solid)
			)
			(layer "B.SilkS")
		)
		(fp_rect
			(start -1.24 0.7)
			(end 1.24 -0.7)
			(stroke
				(width 0.05)
				(type solid)
			)
			(fill no)
			(layer "B.CrtYd")
		)
		(fp_rect
			(start -0.8 0.4)
			(end 0.8 -0.4)
			(stroke
				(width 0.15)
				(type solid)
			)
			(fill no)
			(layer "B.Fab")
		)
		(pad "1" smd roundrect
			(at -0.7 0 270)
			(size 0.6 0.8)
			(layers "B.Cu" "B.Mask" "B.Paste")
			(roundrect_rratio 0.2)
			(net 459 "3V3_SYS")
			(pintype "passive")
		)
		(pad "2" smd roundrect
			(at 0.7 0 270)
			(size 0.6 0.8)
			(layers "B.Cu" "B.Mask" "B.Paste")
			(roundrect_rratio 0.2)
			(net 5 "GND")
			(pintype "passive")
		)
	)
	(footprint "antmicro-footprints:C_0603_1608Metric"
		(layer "B.Cu")
		(at 169.036328 105.497157 -90)
		(descr "Capacitor SMD 0603")
		(tags "capacitor 0603")
		(property "Reference" "C95"
			(at 1.002843 -0.363672 90)
			(layer "B.SilkS")
			(effects
				(font
					(size 0.7 0.7)
					(thickness 0.15)
				)
				(justify left bottom mirror)
			)
		)
		(property "Value" "C_47u_0603"
			(at 0 -1.6 90)
			(layer "B.Fab")
			(effects
				(font
					(size 0.7 0.7)
					(thickness 0.15)
				)
				(justify left bottom mirror)
			)
		)
		(property "Description" " "
			(at 0 0 270)
			(layer "F.Fab")
			(hide yes)
			(effects
				(font
					(size 1.27 1.27)
					(thickness 0.15)
				)
			)
		)
		(property "Author" "Antmicro"
			(at 63.539171 274.533485 0)
			(layer "B.Fab")
			(hide yes)
			(effects
				(font
					(size 1 1)
					(thickness 0.15)
				)
				(justify mirror)
			)
		)
		(property "Dielectric" ""
			(at 63.539171 274.533485 0)
			(layer "B.Fab")
			(hide yes)
			(effects
				(font
					(size 1 1)
					(thickness 0.15)
				)
				(justify mirror)
			)
		)
		(property "License" "Apache-2.0"
			(at 63.539171 274.533485 0)
			(layer "B.Fab")
			(hide yes)
			(effects
				(font
					(size 1 1)
					(thickness 0.15)
				)
				(justify mirror)
			)
		)
		(property "MPN" "GRM188R60J476ME15D"
			(at 63.539171 274.533485 0)
			(layer "B.Fab")
			(hide yes)
			(effects
				(font
					(size 1 1)
					(thickness 0.15)
				)
				(justify mirror)
			)
		)
		(property "Manufacturer" "Murata"
			(at 63.539171 274.533485 0)
			(layer "B.Fab")
			(hide yes)
			(effects
				(font
					(size 1 1)
					(thickness 0.15)
				)
				(justify mirror)
			)
		)
		(property "Val" "47u"
			(at 63.539171 274.533485 0)
			(layer "B.Fab")
			(hide yes)
			(effects
				(font
					(size 1 1)
					(thickness 0.15)
				)
				(justify mirror)
			)
		)
		(property "Voltage" ""
			(at 63.539171 274.533485 0)
			(layer "B.Fab")
			(hide yes)
			(effects
				(font
					(size 1 1)
					(thickness 0.15)
				)
				(justify mirror)
			)
		)
		(sheetname "FPGA power")
		(sheetfile "fpga-power.kicad_sch")
		(attr smd)
		(fp_line
			(start -0.3 0.3)
			(end 0.3 0.3)
			(stroke
				(width 0.15)
				(type solid)
			)
			(layer "B.SilkS")
		)
		(fp_line
			(start -0.3 -0.3)
			(end 0.3 -0.3)
			(stroke
				(width 0.15)
				(type solid)
			)
			(layer "B.SilkS")
		)
		(fp_rect
			(start -1.24 0.7)
			(end 1.24 -0.7)
			(stroke
				(width 0.05)
				(type solid)
			)
			(fill no)
			(layer "B.CrtYd")
		)
		(fp_rect
			(start -0.8 0.4)
			(end 0.8 -0.4)
			(stroke
				(width 0.15)
				(type solid)
			)
			(fill no)
			(layer "B.Fab")
		)
		(pad "1" smd roundrect
			(at -0.7 0 270)
			(size 0.6 0.8)
			(layers "B.Cu" "B.Mask" "B.Paste")
			(roundrect_rratio 0.2)
			(net 459 "3V3_SYS")
			(pintype "passive")
		)
		(pad "2" smd roundrect
			(at 0.7 0 270)
			(size 0.6 0.8)
			(layers "B.Cu" "B.Mask" "B.Paste")
			(roundrect_rratio 0.2)
			(net 5 "GND")
			(pintype "passive")
		)
	)
	(footprint "antmicro-footprints:C_0201"
		(layer "B.Cu")
		(at 166.036328 98.372157)
		(descr "Capacitor SMD 0201")
		(tags "capacitor SMD 0201")
		(property "Reference" "C70"
			(at 0.663672 1.077843 180)
			(layer "B.SilkS")
			(effects
				(font
					(size 0.7 0.7)
					(thickness 0.15)
				)
				(justify left bottom mirror)
			)
		)
		(property "Value" "C_100n_0201"
			(at 0 -1.4 180)
			(layer "B.Fab")
			(effects
				(font
					(size 0.7 0.7)
					(thickness 0.15)
				)
				(justify left bottom mirror)
			)
		)
		(property "Description" " "
			(at 0 0 0)
			(layer "F.Fab")
			(hide yes)
			(effects
				(font
					(size 1.27 1.27)
					(thickness 0.15)
				)
			)
		)
		(property "Author" "Antmicro"
			(at 0 0 0)
			(layer "B.Fab")
			(hide yes)
			(effects
				(font
					(size 1 1)
					(thickness 0.15)
				)
				(justify mirror)
			)
		)
		(property "Dielectric" ""
			(at 0 0 0)
			(layer "B.Fab")
			(hide yes)
			(effects
				(font
					(size 1 1)
					(thickness 0.15)
				)
				(justify mirror)
			)
		)
		(property "License" "Apache-2.0"
			(at 0 0 0)
			(layer "B.Fab")
			(hide yes)
			(effects
				(font
					(size 1 1)
					(thickness 0.15)
				)
				(justify mirror)
			)
		)
		(property "MPN" "CC0201KRX6S5BB104"
			(at 0 0 0)
			(layer "B.Fab")
			(hide yes)
			(effects
				(font
					(size 1 1)
					(thickness 0.15)
				)
				(justify mirror)
			)
		)
		(property "Manufacturer" "Yaego"
			(at 0 0 0)
			(layer "B.Fab")
			(hide yes)
			(effects
				(font
					(size 1 1)
					(thickness 0.15)
				)
				(justify mirror)
			)
		)
		(property "Val" "100n"
			(at 0 0 0)
			(layer "B.Fab")
			(hide yes)
			(effects
				(font
					(size 1 1)
					(thickness 0.15)
				)
				(justify mirror)
			)
		)
		(property "Voltage" ""
			(at 0 0 0)
			(layer "B.Fab")
			(hide yes)
			(effects
				(font
					(size 1 1)
					(thickness 0.15)
				)
				(justify mirror)
			)
		)
		(sheetname "FPGA power")
		(sheetfile "fpga-power.kicad_sch")
		(attr smd)
		(fp_rect
			(start -0.72 0.38)
			(end 0.72 -0.38)
			(stroke
				(width 0.05)
				(type solid)
			)
			(fill no)
			(layer "B.CrtYd")
		)
		(fp_rect
			(start 0.3 -0.15)
			(end -0.301 0.149)
			(stroke
				(width 0.15)
				(type solid)
			)
			(fill no)
			(layer "B.Fab")
		)
		(pad "" smd roundrect
			(at -0.349 0.002)
			(size 0.318 0.36)
			(layers "B.Paste")
			(roundrect_rratio 0.25)
		)
		(pad "" smd roundrect
			(at 0.341 0.002)
			(size 0.318 0.36)
			(layers "B.Paste")
			(roundrect_rratio 0.25)
		)
		(pad "1" smd roundrect
			(at -0.321 0.002)
			(size 0.46 0.4)
			(layers "B.Cu" "B.Mask")
			(roundrect_rratio 0.25)
			(net 465 "1V0_SYS")
			(pintype "passive")
		)
		(pad "2" smd roundrect
			(at 0.32 0.002)
			(size 0.46 0.4)
			(layers "B.Cu" "B.Mask")
			(roundrect_rratio 0.25)
			(net 5 "GND")
			(pintype "passive")
		)
	)
)
